(kicad_pcb
	(version 20260206)
	(generator "pcbnew")
	(generator_version "10.0")
	(general
		(thickness 1.6)
		(legacy_teardrops no)
	)
	(paper "A4")
	(title_block
		(title "03242023_DA0F0TMBIJ0_F0T_Motherboard_J_brd_V01_OCP.brd")
		(comment 1 "Grand Teton / footprint 3039 of 6105 (U2), pads 4216-4324 of 4677")
	)
	(layers
		(0 "F.Cu" signal "TOP")
		(4 "In1.Cu" signal "GND")
		(6 "In2.Cu" signal "IN1")
		(8 "In3.Cu" signal "GND1")
		(10 "In4.Cu" signal "IN2")
		(12 "In5.Cu" signal "GND2")
		(14 "In6.Cu" signal "IN3")
		(16 "In7.Cu" signal "GND3")
		(18 "In8.Cu" signal "VCC")
		(20 "In9.Cu" signal "VCC1")
		(22 "In10.Cu" signal "GND4")
		(24 "In11.Cu" signal "IN4")
		(26 "In12.Cu" signal "GND5")
		(28 "In13.Cu" signal "IN5")
		(30 "In14.Cu" signal "GND6")
		(32 "In15.Cu" signal "IN6")
		(34 "In16.Cu" signal "GND7")
		(2 "B.Cu" signal "BOTTOM")
		(9 "F.Adhes" user "F.Adhesive")
		(11 "B.Adhes" user "B.Adhesive")
		(13 "F.Paste" user "Package Geometry/Pastemask Top")
		(15 "B.Paste" user "Package Geometry/Pastemask Bottom")
		(5 "F.SilkS" user "Ref Des/Silkscreen Top")
		(7 "B.SilkS" user "Ref Des/Silkscreen Bottom")
		(1 "F.Mask" user "Board Geometry/Soldermask Top")
		(3 "B.Mask" user "Board Geometry/Soldermask Bottom")
		(17 "Dwgs.User" user "User.Drawings")
		(19 "Cmts.User" user "User.Comments")
		(21 "Eco1.User" user "User.Eco1")
		(23 "Eco2.User" user "User.Eco2")
		(25 "Edge.Cuts" user "Board Geometry/Outline")
		(27 "Margin" user)
		(31 "F.CrtYd" user "Package Geometry/Place Bound Top")
		(29 "B.CrtYd" user "Package Geometry/Place Bound Bottom")
		(35 "F.Fab" user "Ref Des/Assembly Top")
		(33 "B.Fab" user "Ref Des/Assembly Bottom")
	)
	(footprint ""
		(layer "F.Cu")
		(at 359.870248 -251.76988 90)
		(property "Reference" "U2"
			(at -74.416158 -44.488608 0)
			(unlocked yes)
			(layer "F.SilkS")
			(effects
				(font
					(size 1.6002 1.1938)
					(thickness 0.1524)
				)
				(justify left)
			)
		)
		(property "Value" ""
			(at 0 0 90)
			(layer "F.Fab")
			(effects
				(font
					(size 1.27 1.27)
				)
			)
		)
		(duplicate_pad_numbers_are_jumpers no)
		(pad "K63" smd circle
			(at 14.635988 -22.735286 270)
			(size 0.4318 0.4318)
			(layers "F.Cu" "F.Mask" "F.Paste")
			(net "M_B_CPU0_SA_DQ<16>")
		)
		(pad "K65" smd circle
			(at 16.263874 -22.735286 270)
			(size 0.4318 0.4318)
			(layers "F.Cu" "F.Mask" "F.Paste")
			(net "M_A_CPU0_SA_DQ<13>")
		)
		(pad "K67" smd circle
			(at 17.89176 -22.735286 270)
			(size 0.4318 0.4318)
			(layers "F.Cu" "F.Mask" "F.Paste")
			(net "M_A_CPU0_SA_DQS_DP<1>")
		)
		(pad "K69" smd circle
			(at 19.519392 -22.735286 270)
			(size 0.4318 0.4318)
			(layers "F.Cu" "F.Mask" "F.Paste")
			(net "M_A_CPU0_SA_DQ<8>")
		)
		(pad "K71" smd circle
			(at 21.147278 -22.735286 270)
			(size 0.4318 0.4318)
			(layers "F.Cu" "F.Mask" "F.Paste")
			(net "M_B_CPU0_SA_DQ<5>")
		)
		(pad "K73" smd circle
			(at 22.77491 -22.735286 270)
			(size 0.4318 0.4318)
			(layers "F.Cu" "F.Mask" "F.Paste")
			(net "M_B_CPU0_SA_DQS_DP<0>")
		)
		(pad "K75" smd circle
			(at 24.402796 -22.735286 270)
			(size 0.4318 0.4318)
			(layers "F.Cu" "F.Mask" "F.Paste")
			(net "M_B_CPU0_SA_DQ<0>")
		)
		(pad "K77" smd circle
			(at 26.030682 -22.735286 270)
			(size 0.4318 0.4318)
			(layers "F.Cu" "F.Mask" "F.Paste")
			(net "GND")
		)
		(pad "K79" smd circle
			(at 27.658314 -22.735286 270)
			(size 0.4318 0.4318)
			(layers "F.Cu" "F.Mask" "F.Paste")
			(net "UPI_CPU1_CPU0_P2P2_DN<20>")
		)
		(pad "K81" smd circle
			(at 29.2862 -22.735286 270)
			(size 0.4318 0.4318)
			(layers "F.Cu" "F.Mask" "F.Paste")
			(net "UPI_CPU1_CPU0_P2P2_DP<18>")
		)
		(pad "K83" smd circle
			(at 30.914086 -22.735286 270)
			(size 0.4318 0.4318)
			(layers "F.Cu" "F.Mask" "F.Paste")
			(net "GND")
		)
		(pad "K85" smd circle
			(at 32.541718 -22.735286 270)
			(size 0.4318 0.4318)
			(layers "F.Cu" "F.Mask" "F.Paste")
			(net "GND")
		)
		(pad "K87" smd circle
			(at 34.169604 -22.735286 270)
			(size 0.4318 0.4318)
			(layers "F.Cu" "F.Mask" "F.Paste")
			(net "PVCCFA_EHV_FIVRA_CPU0")
		)
		(pad "K89" smd circle
			(at 35.797236 -22.735286 270)
			(size 0.4318 0.4318)
			(layers "F.Cu" "F.Mask" "F.Paste")
			(net "P5E_CPU0_PE4_RX_DP<0>")
		)
		(pad "L3" smd circle
			(at -35.797236 -22.375114 270)
			(size 0.4318 0.4318)
			(layers "F.Cu" "F.Mask" "F.Paste")
			(net "UPI_CPU0_CPU1_P0P1_DP<1>")
		)
		(pad "L5" smd circle
			(at -34.169604 -22.375114 270)
			(size 0.4318 0.4318)
			(layers "F.Cu" "F.Mask" "F.Paste")
			(net "GND")
		)
		(pad "L7" smd circle
			(at -32.541718 -22.375114 270)
			(size 0.4318 0.4318)
			(layers "F.Cu" "F.Mask" "F.Paste")
			(net "UPI_CPU1_CPU0_P1P0_DP<0>")
		)
		(pad "L9" smd circle
			(at -30.914086 -22.375114 270)
			(size 0.4318 0.4318)
			(layers "F.Cu" "F.Mask" "F.Paste")
			(net "GND")
		)
		(pad "L11" smd circle
			(at -29.2862 -22.375114 270)
			(size 0.4318 0.4318)
			(layers "F.Cu" "F.Mask" "F.Paste")
			(net "P5E_CPU0_PE0_RX_DP<0>")
		)
		(pad "L13" smd circle
			(at -27.658314 -22.375114 270)
			(size 0.4318 0.4318)
			(layers "F.Cu" "F.Mask" "F.Paste")
			(net "GND")
		)
		(pad "L15" smd circle
			(at -26.030682 -22.375114 270)
			(size 0.4318 0.4318)
			(layers "F.Cu" "F.Mask" "F.Paste")
			(net "GND")
		)
		(pad "L17" smd circle
			(at -24.402796 -22.375114 270)
			(size 0.4318 0.4318)
			(layers "F.Cu" "F.Mask" "F.Paste")
			(net "GND")
		)
		(pad "L19" smd circle
			(at -22.77491 -22.375114 270)
			(size 0.4318 0.4318)
			(layers "F.Cu" "F.Mask" "F.Paste")
			(net "GND")
		)
		(pad "L21" smd circle
			(at -21.147278 -22.375114 270)
			(size 0.4318 0.4318)
			(layers "F.Cu" "F.Mask" "F.Paste")
			(net "GND")
		)
		(pad "L23" smd circle
			(at -19.519392 -22.375114 270)
			(size 0.4318 0.4318)
			(layers "F.Cu" "F.Mask" "F.Paste")
			(net "GND")
		)
		(pad "L25" smd circle
			(at -17.89176 -22.375114 270)
			(size 0.4318 0.4318)
			(layers "F.Cu" "F.Mask" "F.Paste")
			(net "GND")
		)
		(pad "L27" smd circle
			(at -16.263874 -22.375114 270)
			(size 0.4318 0.4318)
			(layers "F.Cu" "F.Mask" "F.Paste")
			(net "GND")
		)
		(pad "L29" smd circle
			(at -14.635988 -22.375114 270)
			(size 0.4318 0.4318)
			(layers "F.Cu" "F.Mask" "F.Paste")
			(net "GND")
		)
		(pad "L31" smd circle
			(at -13.008356 -22.375114 270)
			(size 0.4318 0.4318)
			(layers "F.Cu" "F.Mask" "F.Paste")
			(net "GND")
		)
		(pad "L33" smd circle
			(at -11.380724 -22.375114 270)
			(size 0.4318 0.4318)
			(layers "F.Cu" "F.Mask" "F.Paste")
			(net "GND")
		)
		(pad "L35" smd circle
			(at -9.752838 -22.375114 270)
			(size 0.4318 0.4318)
			(layers "F.Cu" "F.Mask" "F.Paste")
			(net "GND")
		)
		(pad "L37" smd circle
			(at -8.124952 -22.375114 270)
			(size 0.4318 0.4318)
			(layers "F.Cu" "F.Mask" "F.Paste")
			(net "GND")
		)
		(pad "L39" smd circle
			(at -6.49732 -22.375114 270)
			(size 0.4318 0.4318)
			(layers "F.Cu" "F.Mask" "F.Paste")
			(net "GND")
		)
		(pad "L41" smd circle
			(at -4.869434 -22.375114 270)
			(size 0.4318 0.4318)
			(layers "F.Cu" "F.Mask" "F.Paste")
			(net "GND")
		)
		(pad "L43" smd circle
			(at -3.241802 -22.375114 270)
			(size 0.4318 0.4318)
			(layers "F.Cu" "F.Mask" "F.Paste")
			(net "GND")
		)
		(pad "L45" smd circle
			(at -1.613916 -22.375114 270)
			(size 0.4318 0.4318)
			(layers "F.Cu" "F.Mask" "F.Paste")
			(net "GND")
		)
		(pad "L48" smd circle
			(at 2.427732 -22.265386 270)
			(size 0.4318 0.4318)
			(layers "F.Cu" "F.Mask" "F.Paste")
			(net "GND")
		)
		(pad "L50" smd circle
			(at 4.055618 -22.265386 270)
			(size 0.4318 0.4318)
			(layers "F.Cu" "F.Mask" "F.Paste")
			(net "GND")
		)
		(pad "L52" smd circle
			(at 5.68325 -22.265386 270)
			(size 0.4318 0.4318)
			(layers "F.Cu" "F.Mask" "F.Paste")
			(net "GND")
		)
		(pad "L54" smd circle
			(at 7.311136 -22.265386 270)
			(size 0.4318 0.4318)
			(layers "F.Cu" "F.Mask" "F.Paste")
			(net "GND")
		)
		(pad "L56" smd circle
			(at 8.939022 -22.265386 270)
			(size 0.4318 0.4318)
			(layers "F.Cu" "F.Mask" "F.Paste")
			(net "GND")
		)
		(pad "L58" smd circle
			(at 10.566654 -22.265386 270)
			(size 0.4318 0.4318)
			(layers "F.Cu" "F.Mask" "F.Paste")
			(net "GND")
		)
		(pad "L60" smd circle
			(at 12.19454 -22.265386 270)
			(size 0.4318 0.4318)
			(layers "F.Cu" "F.Mask" "F.Paste")
			(net "GND")
		)
		(pad "L62" smd circle
			(at 13.822426 -22.265386 270)
			(size 0.4318 0.4318)
			(layers "F.Cu" "F.Mask" "F.Paste")
			(net "GND")
		)
		(pad "L64" smd circle
			(at 15.450058 -22.265386 270)
			(size 0.4318 0.4318)
			(layers "F.Cu" "F.Mask" "F.Paste")
			(net "GND")
		)
		(pad "L66" smd circle
			(at 17.07769 -22.265386 270)
			(size 0.4318 0.4318)
			(layers "F.Cu" "F.Mask" "F.Paste")
			(net "GND")
		)
		(pad "L68" smd circle
			(at 18.705576 -22.265386 270)
			(size 0.4318 0.4318)
			(layers "F.Cu" "F.Mask" "F.Paste")
			(net "GND")
		)
		(pad "L70" smd circle
			(at 20.333462 -22.265386 270)
			(size 0.4318 0.4318)
			(layers "F.Cu" "F.Mask" "F.Paste")
			(net "GND")
		)
		(pad "L72" smd circle
			(at 21.961094 -22.265386 270)
			(size 0.4318 0.4318)
			(layers "F.Cu" "F.Mask" "F.Paste")
			(net "GND")
		)
		(pad "L74" smd circle
			(at 23.58898 -22.265386 270)
			(size 0.4318 0.4318)
			(layers "F.Cu" "F.Mask" "F.Paste")
			(net "GND")
		)
		(pad "L76" smd circle
			(at 25.216612 -22.265386 270)
			(size 0.4318 0.4318)
			(layers "F.Cu" "F.Mask" "F.Paste")
			(net "GND")
		)
		(pad "L78" smd circle
			(at 26.844498 -22.265386 270)
			(size 0.4318 0.4318)
			(layers "F.Cu" "F.Mask" "F.Paste")
			(net "GND")
		)
		(pad "L80" smd circle
			(at 28.472384 -22.265386 270)
			(size 0.4318 0.4318)
			(layers "F.Cu" "F.Mask" "F.Paste")
			(net "UPI_CPU1_CPU0_P2P2_DN<18>")
		)
		(pad "L82" smd circle
			(at 30.100016 -22.265386 270)
			(size 0.4318 0.4318)
			(layers "F.Cu" "F.Mask" "F.Paste")
			(net "UPI_CPU1_CPU0_P2P2_DP<19>")
		)
		(pad "L84" smd circle
			(at 31.727902 -22.265386 270)
			(size 0.4318 0.4318)
			(layers "F.Cu" "F.Mask" "F.Paste")
			(net "PVCCFA_EHV_FIVRA_CPU0")
		)
		(pad "L86" smd circle
			(at 33.355534 -22.265386 270)
			(size 0.4318 0.4318)
			(layers "F.Cu" "F.Mask" "F.Paste")
			(net "P5E_CPU0_PE4_TX_DN<0>")
		)
		(pad "L88" smd circle
			(at 34.98342 -22.265386 270)
			(size 0.4318 0.4318)
			(layers "F.Cu" "F.Mask" "F.Paste")
			(net "GND")
		)
		(pad "L90" smd oval
			(at 36.611306 -22.265386)
			(size 0.381 0.4826)
			(drill
				(offset 0 -0.0508)
			)
			(layers "F.Cu" "F.Mask" "F.Paste")
			(net "GND")
		)
		(pad "M2" smd oval
			(at -36.611306 -21.905468 180)
			(size 0.381 0.4826)
			(drill
				(offset 0 -0.0508)
			)
			(layers "F.Cu" "F.Mask" "F.Paste")
			(net "UPI_CPU0_CPU1_P0P1_DN<1>")
		)
		(pad "M4" smd circle
			(at -34.98342 -21.905468 270)
			(size 0.4318 0.4318)
			(layers "F.Cu" "F.Mask" "F.Paste")
			(net "GND")
		)
		(pad "M6" smd circle
			(at -33.355534 -21.905468 270)
			(size 0.4318 0.4318)
			(layers "F.Cu" "F.Mask" "F.Paste")
			(net "UPI_CPU1_CPU0_P1P0_DP<1>")
		)
		(pad "M8" smd circle
			(at -31.727902 -21.905468 270)
			(size 0.4318 0.4318)
			(layers "F.Cu" "F.Mask" "F.Paste")
			(net "GND")
		)
		(pad "M10" smd circle
			(at -30.100016 -21.905468 270)
			(size 0.4318 0.4318)
			(layers "F.Cu" "F.Mask" "F.Paste")
			(net "P5E_CPU0_PE0_RX_DN<1>")
		)
		(pad "M12" smd circle
			(at -28.472384 -21.905468 270)
			(size 0.4318 0.4318)
			(layers "F.Cu" "F.Mask" "F.Paste")
			(net "GND")
		)
		(pad "M14" smd circle
			(at -26.844498 -21.905468 270)
			(size 0.4318 0.4318)
			(layers "F.Cu" "F.Mask" "F.Paste")
			(net "P5E_CPU0_PE0_TX_DP<0>")
		)
		(pad "M16" smd circle
			(at -25.216612 -21.905468 270)
			(size 0.4318 0.4318)
			(layers "F.Cu" "F.Mask" "F.Paste")
			(net "M_B_CPU0_SB_DQ<23>")
		)
		(pad "M18" smd circle
			(at -23.58898 -21.905468 270)
			(size 0.4318 0.4318)
			(layers "F.Cu" "F.Mask" "F.Paste")
			(net "M_B_CPU0_SB_DQS_DN<7>")
		)
		(pad "M20" smd circle
			(at -21.961094 -21.905468 270)
			(size 0.4318 0.4318)
			(layers "F.Cu" "F.Mask" "F.Paste")
			(net "M_B_CPU0_SB_DQ<18>")
		)
		(pad "M22" smd circle
			(at -20.333462 -21.905468 270)
			(size 0.4318 0.4318)
			(layers "F.Cu" "F.Mask" "F.Paste")
			(net "M_B_CPU0_SB_DQ<15>")
		)
		(pad "M24" smd circle
			(at -18.705576 -21.905468 270)
			(size 0.4318 0.4318)
			(layers "F.Cu" "F.Mask" "F.Paste")
			(net "M_B_CPU0_SB_DQS_DN<6>")
		)
		(pad "M26" smd circle
			(at -17.07769 -21.905468 270)
			(size 0.4318 0.4318)
			(layers "F.Cu" "F.Mask" "F.Paste")
			(net "M_B_CPU0_SB_DQ<10>")
		)
		(pad "M28" smd circle
			(at -15.450058 -21.905468 270)
			(size 0.4318 0.4318)
			(layers "F.Cu" "F.Mask" "F.Paste")
			(net "M_A_CPU0_SB_DQ<7>")
		)
		(pad "M30" smd circle
			(at -13.822426 -21.905468 270)
			(size 0.4318 0.4318)
			(layers "F.Cu" "F.Mask" "F.Paste")
			(net "M_A_CPU0_SB_DQS_DN<5>")
		)
		(pad "M32" smd circle
			(at -12.19454 -21.905468 270)
			(size 0.4318 0.4318)
			(layers "F.Cu" "F.Mask" "F.Paste")
			(net "M_A_CPU0_SB_DQ<2>")
		)
		(pad "M34" smd circle
			(at -10.566654 -21.905468 270)
			(size 0.4318 0.4318)
			(layers "F.Cu" "F.Mask" "F.Paste")
			(net "M_B_CPU0_SB_CB<3>")
		)
		(pad "M36" smd circle
			(at -8.939022 -21.905468 270)
			(size 0.4318 0.4318)
			(layers "F.Cu" "F.Mask" "F.Paste")
			(net "M_B_CPU0_SB_DQS_DP<4>")
		)
		(pad "M38" smd circle
			(at -7.311136 -21.905468 270)
			(size 0.4318 0.4318)
			(layers "F.Cu" "F.Mask" "F.Paste")
			(net "M_B_CPU0_SB_CB<6>")
		)
		(pad "M40" smd circle
			(at -5.68325 -21.905468 270)
			(size 0.4318 0.4318)
			(layers "F.Cu" "F.Mask" "F.Paste")
			(net "M_B_CPU0_SB_CS_N<3>")
		)
		(pad "M42" smd circle
			(at -4.055618 -21.905468 270)
			(size 0.4318 0.4318)
			(layers "F.Cu" "F.Mask" "F.Paste")
			(net "GND")
		)
		(pad "M44" smd circle
			(at -2.427732 -21.905468 270)
			(size 0.4318 0.4318)
			(layers "F.Cu" "F.Mask" "F.Paste")
			(net "M_B_CPU0_SB_CA<3>")
		)
		(pad "M47" smd circle
			(at 1.613916 -21.795486 270)
			(size 0.4318 0.4318)
			(layers "F.Cu" "F.Mask" "F.Paste")
			(net "M_B_CPU0_SA_CA<5>")
		)
		(pad "M49" smd circle
			(at 3.241802 -21.795486 270)
			(size 0.4318 0.4318)
			(layers "F.Cu" "F.Mask" "F.Paste")
			(net "GND")
		)
		(pad "M51" smd circle
			(at 4.869434 -21.795486 270)
			(size 0.4318 0.4318)
			(layers "F.Cu" "F.Mask" "F.Paste")
			(net "M_B_CPU0_SA_CS_N<2>")
		)
		(pad "M53" smd circle
			(at 6.49732 -21.795486 270)
			(size 0.4318 0.4318)
			(layers "F.Cu" "F.Mask" "F.Paste")
			(net "M_B_CPU0_SA_CB<7>")
		)
		(pad "M55" smd circle
			(at 8.124952 -21.795486 270)
			(size 0.4318 0.4318)
			(layers "F.Cu" "F.Mask" "F.Paste")
			(net "M_B_CPU0_SA_DQS_DN<9>")
		)
		(pad "M57" smd circle
			(at 9.752838 -21.795486 270)
			(size 0.4318 0.4318)
			(layers "F.Cu" "F.Mask" "F.Paste")
			(net "M_B_CPU0_SA_CB<2>")
		)
		(pad "M59" smd circle
			(at 11.380724 -21.795486 270)
			(size 0.4318 0.4318)
			(layers "F.Cu" "F.Mask" "F.Paste")
			(net "M_B_CPU0_SA_DQ<23>")
		)
		(pad "M61" smd circle
			(at 13.008356 -21.795486 270)
			(size 0.4318 0.4318)
			(layers "F.Cu" "F.Mask" "F.Paste")
			(net "M_B_CPU0_SA_DQS_DN<7>")
		)
		(pad "M63" smd circle
			(at 14.635988 -21.795486 270)
			(size 0.4318 0.4318)
			(layers "F.Cu" "F.Mask" "F.Paste")
			(net "M_B_CPU0_SA_DQ<18>")
		)
		(pad "M65" smd circle
			(at 16.263874 -21.795486 270)
			(size 0.4318 0.4318)
			(layers "F.Cu" "F.Mask" "F.Paste")
			(net "M_A_CPU0_SA_DQ<15>")
		)
		(pad "M67" smd circle
			(at 17.89176 -21.795486 270)
			(size 0.4318 0.4318)
			(layers "F.Cu" "F.Mask" "F.Paste")
			(net "M_A_CPU0_SA_DQS_DP<6>")
		)
		(pad "M69" smd circle
			(at 19.519392 -21.795486 270)
			(size 0.4318 0.4318)
			(layers "F.Cu" "F.Mask" "F.Paste")
			(net "M_A_CPU0_SA_DQ<10>")
		)
		(pad "M71" smd circle
			(at 21.147278 -21.795486 270)
			(size 0.4318 0.4318)
			(layers "F.Cu" "F.Mask" "F.Paste")
			(net "M_B_CPU0_SA_DQ<7>")
		)
		(pad "M73" smd circle
			(at 22.77491 -21.795486 270)
			(size 0.4318 0.4318)
			(layers "F.Cu" "F.Mask" "F.Paste")
			(net "M_B_CPU0_SA_DQS_DN<5>")
		)
		(pad "M75" smd circle
			(at 24.402796 -21.795486 270)
			(size 0.4318 0.4318)
			(layers "F.Cu" "F.Mask" "F.Paste")
			(net "M_B_CPU0_SA_DQ<2>")
		)
		(pad "M77" smd circle
			(at 26.030682 -21.795486 270)
			(size 0.4318 0.4318)
			(layers "F.Cu" "F.Mask" "F.Paste")
			(net "M_A_CPU0_SA_DQ<2>")
		)
		(pad "M79" smd circle
			(at 27.658314 -21.795486 270)
			(size 0.4318 0.4318)
			(layers "F.Cu" "F.Mask" "F.Paste")
			(net "UPI_CPU1_CPU0_P2P2_DP<20>")
		)
		(pad "M81" smd circle
			(at 29.2862 -21.795486 270)
			(size 0.4318 0.4318)
			(layers "F.Cu" "F.Mask" "F.Paste")
			(net "GND")
		)
		(pad "M83" smd circle
			(at 30.914086 -21.795486 270)
			(size 0.4318 0.4318)
			(layers "F.Cu" "F.Mask" "F.Paste")
			(net "GND")
		)
		(pad "M85" smd circle
			(at 32.541718 -21.795486 270)
			(size 0.4318 0.4318)
			(layers "F.Cu" "F.Mask" "F.Paste")
			(net "PVCCFA_EHV_FIVRA_CPU0")
		)
		(pad "M87" smd circle
			(at 34.169604 -21.795486 270)
			(size 0.4318 0.4318)
			(layers "F.Cu" "F.Mask" "F.Paste")
			(net "P5E_CPU0_PE4_TX_DP<0>")
		)
		(pad "M89" smd circle
			(at 35.797236 -21.795486 270)
			(size 0.4318 0.4318)
			(layers "F.Cu" "F.Mask" "F.Paste")
			(net "PVCCFA_EHV_FIVRA_CPU0")
		)
		(pad "N1" smd oval
			(at -37.425122 -21.435314 180)
			(size 0.381 0.4826)
			(drill
				(offset 0 -0.0508)
			)
			(layers "F.Cu" "F.Mask" "F.Paste")
			(net "UPI_CPU0_CPU1_P0P1_DN<2>")
		)
		(pad "N3" smd circle
			(at -35.797236 -21.435314 270)
			(size 0.4318 0.4318)
			(layers "F.Cu" "F.Mask" "F.Paste")
			(net "PVCCFA_EHV_CPU0")
		)
		(pad "N5" smd circle
			(at -34.169604 -21.435314 270)
			(size 0.4318 0.4318)
			(layers "F.Cu" "F.Mask" "F.Paste")
			(net "UPI_CPU1_CPU0_P1P0_DN<1>")
		)
		(pad "N7" smd circle
			(at -32.541718 -21.435314 270)
			(size 0.4318 0.4318)
			(layers "F.Cu" "F.Mask" "F.Paste")
			(net "PVCCFA_EHV_FIVRA_CPU0")
		)
		(pad "N9" smd circle
			(at -30.914086 -21.435314 270)
			(size 0.4318 0.4318)
			(layers "F.Cu" "F.Mask" "F.Paste")
			(net "P5E_CPU0_PE0_RX_DP<1>")
		)
		(pad "N11" smd circle
			(at -29.2862 -21.435314 270)
			(size 0.4318 0.4318)
			(layers "F.Cu" "F.Mask" "F.Paste")
			(net "PVCCFA_EHV_FIVRA_CPU0")
		)
		(pad "N13" smd circle
			(at -27.658314 -21.435314 270)
			(size 0.4318 0.4318)
			(layers "F.Cu" "F.Mask" "F.Paste")
			(net "P5E_CPU0_PE0_TX_DN<0>")
		)
	)
)
